# S9S_MB_2U (Grand Teton) — schematic netlist excerpt (pin names and nets, part order shuffled) for the footprints in the layout excerpt that follows; sources: Cadence DE-HDL packaged netlist, KiCad conversion of 03242023_DA0F0TMBIJ0_F0T_Motherboard_J_brd_V01_OCP.brd

R2803  Q_RES  0 5% CHIP  pkg 0402LF  page 245 : A = FM_FAN_PWR_EN_R ; B = FM_FAN_PWR_EN
C2032  Q_CAP  0.1UF 25V 10% X7R  pkg 0402  page 152 : A = P3V3_AUX_USB_HUB ; B = GND
C454  Q_CAP  47UF 4V 20% X6S  pkg C0805  page 79 : A = PVCCFA_EHV_FIVRA_CPU1 ; B = GND

(kicad_pcb
	(version 20260206)
	(generator "pcbnew")
	(generator_version "10.0")
	(general
		(thickness 1.6)
		(legacy_teardrops no)
	)
	(paper "A4")
	(title_block
		(title "03242023_DA0F0TMBIJ0_F0T_Motherboard_J_brd_V01_OCP.brd")
		(comment 1 "Grand Teton / footprints 5330-5332 of 6105")
	)
	(layers
		(0 "F.Cu" signal "TOP")
		(4 "In1.Cu" signal "GND")
		(6 "In2.Cu" signal "IN1")
		(8 "In3.Cu" signal "GND1")
		(10 "In4.Cu" signal "IN2")
		(12 "In5.Cu" signal "GND2")
		(14 "In6.Cu" signal "IN3")
		(16 "In7.Cu" signal "GND3")
		(18 "In8.Cu" signal "VCC")
		(20 "In9.Cu" signal "VCC1")
		(22 "In10.Cu" signal "GND4")
		(24 "In11.Cu" signal "IN4")
		(26 "In12.Cu" signal "GND5")
		(28 "In13.Cu" signal "IN5")
		(30 "In14.Cu" signal "GND6")
		(32 "In15.Cu" signal "IN6")
		(34 "In16.Cu" signal "GND7")
		(2 "B.Cu" signal "BOTTOM")
		(9 "F.Adhes" user "F.Adhesive")
		(11 "B.Adhes" user "B.Adhesive")
		(13 "F.Paste" user "Package Geometry/Pastemask Top")
		(15 "B.Paste" user "Package Geometry/Pastemask Bottom")
		(5 "F.SilkS" user "Ref Des/Silkscreen Top")
		(7 "B.SilkS" user "Ref Des/Silkscreen Bottom")
		(1 "F.Mask" user "Board Geometry/Soldermask Top")
		(3 "B.Mask" user "Board Geometry/Soldermask Bottom")
		(17 "Dwgs.User" user "User.Drawings")
		(19 "Cmts.User" user "User.Comments")
		(21 "Eco1.User" user "User.Eco1")
		(23 "Eco2.User" user "User.Eco2")
		(25 "Edge.Cuts" user "Board Geometry/Outline")
		(27 "Margin" user)
		(31 "F.CrtYd" user "Package Geometry/Place Bound Top")
		(29 "B.CrtYd" user "Package Geometry/Place Bound Bottom")
		(35 "F.Fab" user "Ref Des/Assembly Top")
		(33 "B.Fab" user "Ref Des/Assembly Bottom")
	)
	(footprint ""
		(layer "B.Cu")
		(at 16.208502 -98.669348)
		(property "Reference" "C2032"
			(at 0 0 0)
			(layer "B.SilkS")
			(hide yes)
			(effects
				(font
					(size 1.27 1.27)
				)
				(justify mirror)
			)
		)
		(property "Value" ""
			(at 0 0 0)
			(layer "B.Fab")
			(effects
				(font
					(size 1.27 1.27)
				)
				(justify mirror)
			)
		)
		(duplicate_pad_numbers_are_jumpers no)
		(fp_line
			(start -0.7874 -0.4064)
			(end -0.7874 0.4064)
			(stroke
				(width 0.1524)
				(type default)
			)
			(layer "B.SilkS")
		)
		(fp_line
			(start -0.7874 0.4064)
			(end 0.7874 0.4064)
			(stroke
				(width 0.1524)
				(type default)
			)
			(layer "B.SilkS")
		)
		(fp_line
			(start 0.7874 -0.4064)
			(end -0.7874 -0.4064)
			(stroke
				(width 0.1524)
				(type default)
			)
			(layer "B.SilkS")
		)
		(fp_line
			(start 0.7874 0.4064)
			(end 0.7874 -0.4064)
			(stroke
				(width 0.1524)
				(type default)
			)
			(layer "B.SilkS")
		)
		(fp_line
			(start -0.67945 -0.3048)
			(end -0.67945 0.3048)
			(stroke
				(width 0.1)
				(type default)
			)
			(layer "B.Fab")
		)
		(fp_line
			(start -0.67945 0.3048)
			(end -0.120396 0.3048)
			(stroke
				(width 0.1)
				(type default)
			)
			(layer "B.Fab")
		)
		(fp_line
			(start -0.12065 -0.3048)
			(end -0.67945 -0.3048)
			(stroke
				(width 0.1)
				(type default)
			)
			(layer "B.Fab")
		)
		(fp_line
			(start -0.12065 -0.2794)
			(end -0.12065 -0.3048)
			(stroke
				(width 0.1)
				(type default)
			)
			(layer "B.Fab")
		)
		(fp_line
			(start -0.120396 0.2794)
			(end 0.12065 0.2794)
			(stroke
				(width 0.1)
				(type default)
			)
			(layer "B.Fab")
		)
		(fp_line
			(start -0.120396 0.3048)
			(end -0.120396 0.2794)
			(stroke
				(width 0.1)
				(type default)
			)
			(layer "B.Fab")
		)
		(fp_line
			(start 0.12065 -0.305054)
			(end 0.12065 -0.2794)
			(stroke
				(width 0.1)
				(type default)
			)
			(layer "B.Fab")
		)
		(fp_line
			(start 0.12065 -0.2794)
			(end -0.12065 -0.2794)
			(stroke
				(width 0.1)
				(type default)
			)
			(layer "B.Fab")
		)
		(fp_line
			(start 0.12065 0.2794)
			(end 0.12065 0.3048)
			(stroke
				(width 0.1)
				(type default)
			)
			(layer "B.Fab")
		)
		(fp_line
			(start 0.12065 0.3048)
			(end 0.67945 0.3048)
			(stroke
				(width 0.1)
				(type default)
			)
			(layer "B.Fab")
		)
		(fp_line
			(start 0.67945 -0.305054)
			(end 0.12065 -0.305054)
			(stroke
				(width 0.1)
				(type default)
			)
			(layer "B.Fab")
		)
		(fp_line
			(start 0.67945 0.3048)
			(end 0.67945 -0.305054)
			(stroke
				(width 0.1)
				(type default)
			)
			(layer "B.Fab")
		)
		(pad "1" smd circle
			(at 0.40005 0 180)
			(size 0 0)
			(layers "B.Cu" "B.Mask" "B.Paste")
			(net "P3V3_AUX_USB_HUB")
		)
		(pad "2" smd circle
			(at -0.40005 0 180)
			(size 0 0)
			(layers "B.Cu" "B.Mask" "B.Paste")
			(net "GND")
		)
	)
	(footprint ""
		(layer "B.Cu")
		(at 63.017908 -258.465066 -90)
		(property "Reference" "C454"
			(at 0 0 90)
			(layer "B.SilkS")
			(hide yes)
			(effects
				(font
					(size 1.27 1.27)
				)
				(justify mirror)
			)
		)
		(property "Value" ""
			(at 0 0 90)
			(layer "B.Fab")
			(effects
				(font
					(size 1.27 1.27)
				)
				(justify mirror)
			)
		)
		(duplicate_pad_numbers_are_jumpers no)
		(fp_line
			(start -1.524 0.762)
			(end 1.524 0.762)
			(stroke
				(width 0.1524)
				(type default)
			)
			(layer "B.SilkS")
		)
		(fp_line
			(start 1.524 0.762)
			(end 1.524 -0.762)
			(stroke
				(width 0.1524)
				(type default)
			)
			(layer "B.SilkS")
		)
		(fp_line
			(start -1.524 -0.762)
			(end -1.524 0.762)
			(stroke
				(width 0.1524)
				(type default)
			)
			(layer "B.SilkS")
		)
		(fp_line
			(start 1.524 -0.762)
			(end -1.524 -0.762)
			(stroke
				(width 0.1524)
				(type default)
			)
			(layer "B.SilkS")
		)
		(fp_line
			(start -1.1049 0.724916)
			(end -1.1049 -0.724916)
			(stroke
				(width 0.1)
				(type default)
			)
			(layer "B.Fab")
		)
		(fp_line
			(start 1.1049 0.724916)
			(end -1.1049 0.724916)
			(stroke
				(width 0.1)
				(type default)
			)
			(layer "B.Fab")
		)
		(fp_line
			(start -1.1049 -0.724916)
			(end 1.1049 -0.724916)
			(stroke
				(width 0.1)
				(type default)
			)
			(layer "B.Fab")
		)
		(fp_line
			(start 1.1049 -0.724916)
			(end 1.1049 0.724916)
			(stroke
				(width 0.1)
				(type default)
			)
			(layer "B.Fab")
		)
		(pad "1" smd rect
			(at 0.889 0 270)
			(size 1.016 1.27)
			(layers "B.Cu" "B.Mask" "B.Paste")
			(net "PVCCFA_EHV_FIVRA_CPU1")
		)
		(pad "2" smd rect
			(at -0.889 0 270)
			(size 1.016 1.27)
			(layers "B.Cu" "B.Mask" "B.Paste")
			(net "GND")
		)
	)
	(footprint ""
		(layer "B.Cu")
		(at 241.3254 -422.9862 90)
		(property "Reference" "R2803"
			(at 0 0 90)
			(layer "B.SilkS")
			(hide yes)
			(effects
				(font
					(size 1.27 1.27)
				)
				(justify mirror)
			)
		)
		(property "Value" ""
			(at 0 0 90)
			(layer "B.Fab")
			(effects
				(font
					(size 1.27 1.27)
				)
				(justify mirror)
			)
		)
		(duplicate_pad_numbers_are_jumpers no)
		(fp_line
			(start 0.7874 -0.4064)
			(end -0.7874 -0.4064)
			(stroke
				(width 0.1524)
				(type default)
			)
			(layer "B.SilkS")
		)
		(fp_line
			(start -0.7874 -0.4064)
			(end -0.7874 0.4064)
			(stroke
				(width 0.1524)
				(type default)
			)
			(layer "B.SilkS")
		)
		(fp_line
			(start 0.7874 0.4064)
			(end 0.7874 -0.4064)
			(stroke
				(width 0.1524)
				(type default)
			)
			(layer "B.SilkS")
		)
		(fp_line
			(start -0.7874 0.4064)
			(end 0.7874 0.4064)
			(stroke
				(width 0.1524)
				(type default)
			)
			(layer "B.SilkS")
		)
		(fp_line
			(start 0.67945 -0.305054)
			(end 0.12065 -0.305054)
			(stroke
				(width 0.1)
				(type default)
			)
			(layer "B.Fab")
		)
		(fp_line
			(start 0.12065 -0.305054)
			(end 0.12065 -0.2794)
			(stroke
				(width 0.1)
				(type default)
			)
			(layer "B.Fab")
		)
		(fp_line
			(start -0.12065 -0.3048)
			(end -0.67945 -0.3048)
			(stroke
				(width 0.1)
				(type default)
			)
			(layer "B.Fab")
		)
		(fp_line
			(start -0.67945 -0.3048)
			(end -0.67945 0.3048)
			(stroke
				(width 0.1)
				(type default)
			)
			(layer "B.Fab")
		)
		(fp_line
			(start 0.12065 -0.2794)
			(end -0.12065 -0.2794)
			(stroke
				(width 0.1)
				(type default)
			)
			(layer "B.Fab")
		)
		(fp_line
			(start -0.12065 -0.2794)
			(end -0.12065 -0.3048)
			(stroke
				(width 0.1)
				(type default)
			)
			(layer "B.Fab")
		)
		(fp_line
			(start 0.12065 0.2794)
			(end 0.12065 0.3048)
			(stroke
				(width 0.1)
				(type default)
			)
			(layer "B.Fab")
		)
		(fp_line
			(start -0.120396 0.2794)
			(end 0.12065 0.2794)
			(stroke
				(width 0.1)
				(type default)
			)
			(layer "B.Fab")
		)
		(fp_line
			(start 0.67945 0.3048)
			(end 0.67945 -0.305054)
			(stroke
				(width 0.1)
				(type default)
			)
			(layer "B.Fab")
		)
		(fp_line
			(start 0.12065 0.3048)
			(end 0.67945 0.3048)
			(stroke
				(width 0.1)
				(type default)
			)
			(layer "B.Fab")
		)
		(fp_line
			(start -0.120396 0.3048)
			(end -0.120396 0.2794)
			(stroke
				(width 0.1)
				(type default)
			)
			(layer "B.Fab")
		)
		(fp_line
			(start -0.67945 0.3048)
			(end -0.120396 0.3048)
			(stroke
				(width 0.1)
				(type default)
			)
			(layer "B.Fab")
		)
		(pad "1" smd circle
			(at 0.40005 0 270)
			(size 0 0)
			(layers "B.Cu" "B.Mask" "B.Paste")
			(net "FM_FAN_PWR_EN_R")
		)
		(pad "2" smd circle
			(at -0.40005 0 270)
			(size 0 0)
			(layers "B.Cu" "B.Mask" "B.Paste")
			(net "FM_FAN_PWR_EN")
		)
	)
)
